(kicad_pcb
	(version 20260206)
	(generator "pcbnew")
	(generator_version "10.0")
	(general
		(thickness 1.6)
		(legacy_teardrops no)
	)
	(paper "A4")
	(title_block
		(title "01162023_DA0F0TEBIF0_F0T_Expander_BD_F_brd_V02_OCP.brd")
		(comment 1 "Grand Teton / footprints 4927-4931 of 9728")
	)
	(layers
		(0 "F.Cu" signal "TOP")
		(4 "In1.Cu" signal "GND")
		(6 "In2.Cu" signal "VCC")
		(8 "In3.Cu" signal "VCC1")
		(10 "In4.Cu" signal "GND1")
		(12 "In5.Cu" signal "IN1")
		(14 "In6.Cu" signal "GND2")
		(16 "In7.Cu" signal "IN2")
		(18 "In8.Cu" signal "GND3")
		(20 "In9.Cu" signal "IN3")
		(22 "In10.Cu" signal "GND4")
		(24 "In11.Cu" signal "IN4")
		(26 "In12.Cu" signal "GND5")
		(28 "In13.Cu" signal "IN5")
		(30 "In14.Cu" signal "GND6")
		(32 "In15.Cu" signal "IN6")
		(34 "In16.Cu" signal "GND7")
		(2 "B.Cu" signal "BOTTOM")
		(9 "F.Adhes" user "F.Adhesive")
		(11 "B.Adhes" user "B.Adhesive")
		(13 "F.Paste" user "Package Geometry/Pastemask Top")
		(15 "B.Paste" user "Package Geometry/Pastemask Bottom")
		(5 "F.SilkS" user "Ref Des/Silkscreen Top")
		(7 "B.SilkS" user "Ref Des/Silkscreen Bottom")
		(1 "F.Mask" user "Board Geometry/Soldermask Top")
		(3 "B.Mask" user "Board Geometry/Soldermask Bottom")
		(17 "Dwgs.User" user "User.Drawings")
		(19 "Cmts.User" user "User.Comments")
		(21 "Eco1.User" user "User.Eco1")
		(23 "Eco2.User" user "User.Eco2")
		(25 "Edge.Cuts" user "Board Geometry/Outline")
		(27 "Margin" user)
		(31 "F.CrtYd" user "Package Geometry/Place Bound Top")
		(29 "B.CrtYd" user "Package Geometry/Place Bound Bottom")
		(35 "F.Fab" user "Ref Des/Assembly Top")
		(33 "B.Fab" user "Ref Des/Assembly Bottom")
	)
	(footprint ""
		(layer "F.Cu")
		(at 122.077988 -356.244906 90)
		(property "Reference" "C367"
			(at 0 0 90)
			(layer "F.SilkS")
			(hide yes)
			(effects
				(font
					(size 1.27 1.27)
				)
			)
		)
		(property "Value" ""
			(at 0 0 90)
			(layer "F.Fab")
			(effects
				(font
					(size 1.27 1.27)
				)
			)
		)
		(duplicate_pad_numbers_are_jumpers no)
		(fp_line
			(start 0.299974 -0.150114)
			(end 0.299974 0.150114)
			(stroke
				(width 0.1)
				(type default)
			)
			(layer "F.Fab")
		)
		(fp_line
			(start -0.299974 -0.150114)
			(end 0.299974 -0.150114)
			(stroke
				(width 0.1)
				(type default)
			)
			(layer "F.Fab")
		)
		(fp_line
			(start 0.299974 0.150114)
			(end -0.299974 0.150114)
			(stroke
				(width 0.1)
				(type default)
			)
			(layer "F.Fab")
		)
		(fp_line
			(start -0.299974 0.150114)
			(end -0.299974 -0.150114)
			(stroke
				(width 0.1)
				(type default)
			)
			(layer "F.Fab")
		)
		(pad "1" smd rect
			(at -0.2667 0 90)
			(size 0.3048 0.381)
			(layers "F.Cu" "F.Mask" "F.Paste")
			(net "P5E_PEX1_STN6_TX_DN<98>")
		)
		(pad "2" smd rect
			(at 0.2667 0 90)
			(size 0.3048 0.381)
			(layers "F.Cu" "F.Mask" "F.Paste")
			(net "P5E_PEX1_STN6_TX_C_DN<98>")
		)
	)
	(footprint ""
		(layer "F.Cu")
		(at 361.407202 -275.81606)
		(property "Reference" "PC6622"
			(at 0 0 0)
			(layer "F.SilkS")
			(hide yes)
			(effects
				(font
					(size 1.27 1.27)
				)
			)
		)
		(property "Value" ""
			(at 0 0 0)
			(layer "F.Fab")
			(effects
				(font
					(size 1.27 1.27)
				)
			)
		)
		(duplicate_pad_numbers_are_jumpers no)
		(fp_line
			(start -1.524 -0.762)
			(end 1.524 -0.762)
			(stroke
				(width 0.1524)
				(type default)
			)
			(layer "F.SilkS")
		)
		(fp_line
			(start -1.524 0.762)
			(end -1.524 -0.762)
			(stroke
				(width 0.1524)
				(type default)
			)
			(layer "F.SilkS")
		)
		(fp_line
			(start 1.524 -0.762)
			(end 1.524 0.762)
			(stroke
				(width 0.1524)
				(type default)
			)
			(layer "F.SilkS")
		)
		(fp_line
			(start 1.524 0.762)
			(end -1.524 0.762)
			(stroke
				(width 0.1524)
				(type default)
			)
			(layer "F.SilkS")
		)
		(fp_line
			(start -1.1049 -0.724916)
			(end -1.1049 0.724916)
			(stroke
				(width 0.1)
				(type default)
			)
			(layer "F.Fab")
		)
		(fp_line
			(start -1.1049 0.724916)
			(end 1.1049 0.724916)
			(stroke
				(width 0.1)
				(type default)
			)
			(layer "F.Fab")
		)
		(fp_line
			(start 1.1049 -0.724916)
			(end -1.1049 -0.724916)
			(stroke
				(width 0.1)
				(type default)
			)
			(layer "F.Fab")
		)
		(fp_line
			(start 1.1049 0.724916)
			(end 1.1049 -0.724916)
			(stroke
				(width 0.1)
				(type default)
			)
			(layer "F.Fab")
		)
		(pad "1" smd rect
			(at -0.889 0 180)
			(size 1.016 1.27)
			(layers "F.Cu" "F.Mask" "F.Paste")
			(net "SW_P12V_P0V8_PEX3_FLT")
		)
		(pad "2" smd rect
			(at 0.889 0 180)
			(size 1.016 1.27)
			(layers "F.Cu" "F.Mask" "F.Paste")
			(net "GND")
		)
	)
	(footprint ""
		(layer "F.Cu")
		(at 205.368398 -368.957098 -90)
		(property "Reference" "PU1"
			(at -3.277108 -0.430022 0)
			(unlocked yes)
			(layer "F.SilkS")
			(effects
				(font
					(size 0.7874 0.5842)
					(thickness 0.1524)
				)
			)
		)
		(property "Value" ""
			(at 0 0 270)
			(layer "F.Fab")
			(effects
				(font
					(size 1.27 1.27)
				)
			)
		)
		(duplicate_pad_numbers_are_jumpers no)
		(fp_line
			(start -2.567686 3.567684)
			(end 2.567686 3.567684)
			(stroke
				(width 0.1524)
				(type default)
			)
			(layer "F.SilkS")
		)
		(fp_line
			(start 2.567686 3.567684)
			(end 2.567686 -3.567684)
			(stroke
				(width 0.1524)
				(type default)
			)
			(layer "F.SilkS")
		)
		(fp_line
			(start -2.567686 -3.567684)
			(end -2.567686 3.567684)
			(stroke
				(width 0.1524)
				(type default)
			)
			(layer "F.SilkS")
		)
		(fp_line
			(start 2.567686 -3.567684)
			(end -2.567686 -3.567684)
			(stroke
				(width 0.1524)
				(type default)
			)
			(layer "F.SilkS")
		)
		(fp_poly
			(pts
				(xy -3.02895 -4.209542) (xy -3.747516 -3.49123) (xy -2.669794 -3.13182)
			)
			(stroke
				(width 0)
				(type default)
			)
			(fill yes)
			(layer "F.SilkS")
		)
		(fp_line
			(start -2.549906 3.549904)
			(end 2.549906 3.549904)
			(stroke
				(width 0.1)
				(type default)
			)
			(layer "F.Fab")
		)
		(fp_line
			(start 2.549906 3.549904)
			(end 2.549906 -3.549904)
			(stroke
				(width 0.1)
				(type default)
			)
			(layer "F.Fab")
		)
		(fp_line
			(start -2.549906 -3.549904)
			(end -2.549906 3.549904)
			(stroke
				(width 0.1)
				(type default)
			)
			(layer "F.Fab")
		)
		(fp_line
			(start 2.549906 -3.549904)
			(end -2.549906 -3.549904)
			(stroke
				(width 0.1)
				(type default)
			)
			(layer "F.Fab")
		)
		(fp_poly
			(pts
				(xy -3.7592 -3.20802) (xy -3.7592 -2.19202) (xy -2.7432 -2.70002)
			)
			(stroke
				(width 0)
				(type default)
			)
			(fill yes)
			(layer "F.Fab")
		)
		(pad "1" smd rect
			(at -2.237486 -2.70002)
			(size 0.2286 0.381)
			(layers "F.Cu" "F.Mask" "F.Paste")
			(net "P12V_STBY")
		)
		(pad "2" smd rect
			(at -2.237486 -2.249932)
			(size 0.2286 0.381)
			(layers "F.Cu" "F.Mask" "F.Paste")
			(net "P12V_STBY")
		)
		(pad "3" smd rect
			(at -2.237486 -1.800098)
			(size 0.2286 0.381)
			(layers "F.Cu" "F.Mask" "F.Paste")
			(net "P12V_STBY")
		)
		(pad "4" smd rect
			(at -2.237486 -1.35001)
			(size 0.2286 0.381)
			(layers "F.Cu" "F.Mask" "F.Paste")
			(net "P12V_STBY")
		)
		(pad "5" smd rect
			(at -2.237486 -0.899922)
			(size 0.2286 0.381)
			(layers "F.Cu" "F.Mask" "F.Paste")
			(net "P12V_STBY")
		)
		(pad "6" smd rect
			(at -2.237486 -0.450088)
			(size 0.2286 0.381)
			(layers "F.Cu" "F.Mask" "F.Paste")
			(net "P12V_STBY")
		)
		(pad "7" smd rect
			(at -2.237486 0)
			(size 0.2286 0.381)
			(layers "F.Cu" "F.Mask" "F.Paste")
			(net "P12V_STBY")
		)
		(pad "8" smd rect
			(at -2.237486 0.450088)
			(size 0.2286 0.381)
			(layers "F.Cu" "F.Mask" "F.Paste")
			(net "P12V_STBY")
		)
		(pad "9" smd rect
			(at -2.237486 0.899922)
			(size 0.2286 0.381)
			(layers "F.Cu" "F.Mask" "F.Paste")
			(net "HSC_VINSEN")
		)
		(pad "10" smd rect
			(at -2.237486 1.35001)
			(size 0.2286 0.381)
			(layers "F.Cu" "F.Mask" "F.Paste")
			(net "HSC_ALERT1_N")
		)
		(pad "11" smd rect
			(at -2.237486 1.800098)
			(size 0.2286 0.381)
			(layers "F.Cu" "F.Mask" "F.Paste")
			(net "SMB_HOTSWAP_SCL_R")
		)
		(pad "12" smd rect
			(at -2.237486 2.249932)
			(size 0.2286 0.381)
			(layers "F.Cu" "F.Mask" "F.Paste")
			(net "SMB_HOTSWAP_SDA_R")
		)
		(pad "13" smd rect
			(at -2.237486 2.70002)
			(size 0.2286 0.381)
			(layers "F.Cu" "F.Mask" "F.Paste")
			(net "FM_HSC_PWROK")
		)
		(pad "14" smd rect
			(at -1.575054 3.237484 270)
			(size 0.2286 0.381)
			(layers "F.Cu" "F.Mask" "F.Paste")
			(net "HSC_VIN_UVW_N")
		)
		(pad "15" smd rect
			(at -1.124966 3.237484 270)
			(size 0.2286 0.381)
			(layers "F.Cu" "F.Mask" "F.Paste")
			(net "HSC_VTEMP")
		)
		(pad "16" smd rect
			(at -0.674878 3.237484 270)
			(size 0.2286 0.381)
			(layers "F.Cu" "F.Mask" "F.Paste")
			(net "HSC_SS")
		)
		(pad "17" smd rect
			(at -0.225044 3.237484 270)
			(size 0.2286 0.381)
			(layers "F.Cu" "F.Mask" "F.Paste")
			(net "HSC_VDD_R")
		)
		(pad "18" smd rect
			(at 0.225044 3.237484 270)
			(size 0.2286 0.381)
			(layers "F.Cu" "F.Mask" "F.Paste")
			(net "AGND_HSC")
		)
		(pad "19" smd rect
			(at 0.674878 3.237484 270)
			(size 0.2286 0.381)
			(layers "F.Cu" "F.Mask" "F.Paste")
			(net "HSC_VDD18")
		)
		(pad "20" smd rect
			(at 1.124966 3.237484 270)
			(size 0.2286 0.381)
			(layers "F.Cu" "F.Mask" "F.Paste")
			(net "HSC_CS")
		)
		(pad "21" smd rect
			(at 1.575054 3.237484 270)
			(size 0.2286 0.381)
			(layers "F.Cu" "F.Mask" "F.Paste")
			(net "HSC_IMON")
		)
		(pad "22" smd rect
			(at 2.237486 2.70002)
			(size 0.2286 0.381)
			(layers "F.Cu" "F.Mask" "F.Paste")
			(net "HSC_OCREF")
		)
		(pad "23" smd rect
			(at 2.237486 2.249932)
			(size 0.2286 0.381)
			(layers "F.Cu" "F.Mask" "F.Paste")
			(net "AGND_HSC")
		)
		(pad "24" smd rect
			(at 2.237486 1.800098)
			(size 0.2286 0.381)
			(layers "F.Cu" "F.Mask" "F.Paste")
			(net "HSC_VOSEN")
		)
		(pad "25" smd rect
			(at 2.237486 1.35001)
			(size 0.2286 0.381)
			(layers "F.Cu" "F.Mask" "F.Paste")
			(net "HSC_SCREF")
		)
		(pad "26" smd rect
			(at 2.237486 0.899922)
			(size 0.2286 0.381)
			(layers "F.Cu" "F.Mask" "F.Paste")
			(net "HSC_P12V_MP5990_EN")
		)
		(pad "27" smd rect
			(at 2.237486 0.450088)
			(size 0.2286 0.381)
			(layers "F.Cu" "F.Mask" "F.Paste")
			(net "P12V_AUX")
		)
		(pad "28" smd rect
			(at 2.237486 0)
			(size 0.2286 0.381)
			(layers "F.Cu" "F.Mask" "F.Paste")
			(net "P12V_AUX")
		)
		(pad "29" smd rect
			(at 2.237486 -0.450088)
			(size 0.2286 0.381)
			(layers "F.Cu" "F.Mask" "F.Paste")
			(net "P12V_AUX")
		)
		(pad "30" smd rect
			(at 2.237486 -0.899922)
			(size 0.2286 0.381)
			(layers "F.Cu" "F.Mask" "F.Paste")
			(net "P12V_AUX")
		)
		(pad "31" smd rect
			(at 2.237486 -1.35001)
			(size 0.2286 0.381)
			(layers "F.Cu" "F.Mask" "F.Paste")
			(net "P12V_AUX")
		)
		(pad "32" smd rect
			(at 2.237486 -1.800098)
			(size 0.2286 0.381)
			(layers "F.Cu" "F.Mask" "F.Paste")
			(net "P12V_AUX")
		)
		(pad "33" smd rect
			(at 2.237486 -2.249932)
			(size 0.2286 0.381)
			(layers "F.Cu" "F.Mask" "F.Paste")
			(net "P12V_AUX")
		)
		(pad "34" smd rect
			(at 2.237486 -2.70002)
			(size 0.2286 0.381)
			(layers "F.Cu" "F.Mask" "F.Paste")
			(net "P12V_AUX")
		)
		(pad "35" smd rect
			(at 1.575054 -3.237484 270)
			(size 0.2286 0.381)
			(layers "F.Cu" "F.Mask" "F.Paste")
			(net "P12V_AUX")
		)
		(pad "36" smd rect
			(at 1.124966 -3.237484 270)
			(size 0.2286 0.381)
			(layers "F.Cu" "F.Mask" "F.Paste")
			(net "P12V_AUX")
		)
		(pad "37" smd rect
			(at 0.674878 -3.237484 270)
			(size 0.2286 0.381)
			(layers "F.Cu" "F.Mask" "F.Paste")
			(net "HSC_D_OC")
		)
		(pad "38" smd rect
			(at 0.225044 -3.237484 270)
			(size 0.2286 0.381)
			(layers "F.Cu" "F.Mask" "F.Paste")
			(net "HSC_ON_R")
		)
		(pad "39" smd rect
			(at -0.225044 -3.237484 270)
			(size 0.2286 0.381)
			(layers "F.Cu" "F.Mask" "F.Paste")
			(net "HSC_FAULT_N")
		)
		(pad "40" smd rect
			(at -0.674878 -3.237484 270)
			(size 0.2286 0.381)
			(layers "F.Cu" "F.Mask" "F.Paste")
			(net "HSC_FLT_TYPE")
		)
		(pad "41" smd rect
			(at -1.124966 -3.237484 270)
			(size 0.2286 0.381)
			(layers "F.Cu" "F.Mask" "F.Paste")
			(net "HSC_MODE")
		)
		(pad "42" smd rect
			(at -1.575054 -3.237484 270)
			(size 0.2286 0.381)
			(layers "F.Cu" "F.Mask" "F.Paste")
			(net "P12V_STBY")
		)
		(pad "43" smd rect
			(at 0 -0.999998 270)
			(size 3.4036 3.4036)
			(layers "F.Cu" "F.Mask" "F.Paste")
			(net "P12V_STBY")
		)
		(pad "44" smd rect
			(at -1.124966 1.89992 270)
			(size 1.1684 1.6002)
			(layers "F.Cu" "F.Mask" "F.Paste")
			(net "AGND_HSC")
		)
		(pad "45" smd rect
			(at 1.124966 1.89992 270)
			(size 1.1684 1.6002)
			(layers "F.Cu" "F.Mask" "F.Paste")
			(net "HSC_VDD_R")
		)
	)
	(footprint ""
		(layer "F.Cu")
		(at 146.626834 -53.697124 -90)
		(property "Reference" "PC532"
			(at 0 0 270)
			(layer "F.SilkS")
			(hide yes)
			(effects
				(font
					(size 1.27 1.27)
				)
			)
		)
		(property "Value" ""
			(at 0 0 270)
			(layer "F.Fab")
			(effects
				(font
					(size 1.27 1.27)
				)
			)
		)
		(duplicate_pad_numbers_are_jumpers no)
		(fp_line
			(start -0.7874 0.4064)
			(end -0.7874 -0.4064)
			(stroke
				(width 0.1524)
				(type default)
			)
			(layer "F.SilkS")
		)
		(fp_line
			(start 0.7874 0.4064)
			(end -0.7874 0.4064)
			(stroke
				(width 0.1524)
				(type default)
			)
			(layer "F.SilkS")
		)
		(fp_line
			(start -0.7874 -0.4064)
			(end 0.7874 -0.4064)
			(stroke
				(width 0.1524)
				(type default)
			)
			(layer "F.SilkS")
		)
		(fp_line
			(start 0.7874 -0.4064)
			(end 0.7874 0.4064)
			(stroke
				(width 0.1524)
				(type default)
			)
			(layer "F.SilkS")
		)
		(fp_line
			(start -0.67945 0.3048)
			(end -0.67945 -0.305054)
			(stroke
				(width 0.1)
				(type default)
			)
			(layer "F.Fab")
		)
		(fp_line
			(start -0.12065 0.3048)
			(end -0.67945 0.3048)
			(stroke
				(width 0.1)
				(type default)
			)
			(layer "F.Fab")
		)
		(fp_line
			(start 0.120396 0.3048)
			(end 0.120396 0.2794)
			(stroke
				(width 0.1)
				(type default)
			)
			(layer "F.Fab")
		)
		(fp_line
			(start 0.67945 0.3048)
			(end 0.120396 0.3048)
			(stroke
				(width 0.1)
				(type default)
			)
			(layer "F.Fab")
		)
		(fp_line
			(start -0.12065 0.2794)
			(end -0.12065 0.3048)
			(stroke
				(width 0.1)
				(type default)
			)
			(layer "F.Fab")
		)
		(fp_line
			(start 0.120396 0.2794)
			(end -0.12065 0.2794)
			(stroke
				(width 0.1)
				(type default)
			)
			(layer "F.Fab")
		)
		(fp_line
			(start -0.12065 -0.2794)
			(end 0.12065 -0.2794)
			(stroke
				(width 0.1)
				(type default)
			)
			(layer "F.Fab")
		)
		(fp_line
			(start 0.12065 -0.2794)
			(end 0.12065 -0.3048)
			(stroke
				(width 0.1)
				(type default)
			)
			(layer "F.Fab")
		)
		(fp_line
			(start 0.12065 -0.3048)
			(end 0.67945 -0.3048)
			(stroke
				(width 0.1)
				(type default)
			)
			(layer "F.Fab")
		)
		(fp_line
			(start 0.67945 -0.3048)
			(end 0.67945 0.3048)
			(stroke
				(width 0.1)
				(type default)
			)
			(layer "F.Fab")
		)
		(fp_line
			(start -0.67945 -0.305054)
			(end -0.12065 -0.305054)
			(stroke
				(width 0.1)
				(type default)
			)
			(layer "F.Fab")
		)
		(fp_line
			(start -0.12065 -0.305054)
			(end -0.12065 -0.2794)
			(stroke
				(width 0.1)
				(type default)
			)
			(layer "F.Fab")
		)
		(pad "1" smd circle
			(at -0.40005 0 270)
			(size 0 0)
			(layers "F.Cu" "F.Mask" "F.Paste")
			(net "P3V3_AUX")
		)
		(pad "2" smd circle
			(at 0.40005 0 270)
			(size 0 0)
			(layers "F.Cu" "F.Mask" "F.Paste")
			(net "GND")
		)
	)
	(footprint ""
		(layer "F.Cu")
		(at 143.840708 -356.244906 90)
		(property "Reference" "C2244"
			(at 0 0 90)
			(layer "F.SilkS")
			(hide yes)
			(effects
				(font
					(size 1.27 1.27)
				)
			)
		)
		(property "Value" ""
			(at 0 0 90)
			(layer "F.Fab")
			(effects
				(font
					(size 1.27 1.27)
				)
			)
		)
		(duplicate_pad_numbers_are_jumpers no)
		(fp_line
			(start 0.299974 -0.150114)
			(end 0.299974 0.150114)
			(stroke
				(width 0.1)
				(type default)
			)
			(layer "F.Fab")
		)
		(fp_line
			(start -0.299974 -0.150114)
			(end 0.299974 -0.150114)
			(stroke
				(width 0.1)
				(type default)
			)
			(layer "F.Fab")
		)
		(fp_line
			(start 0.299974 0.150114)
			(end -0.299974 0.150114)
			(stroke
				(width 0.1)
				(type default)
			)
			(layer "F.Fab")
		)
		(fp_line
			(start -0.299974 0.150114)
			(end -0.299974 -0.150114)
			(stroke
				(width 0.1)
				(type default)
			)
			(layer "F.Fab")
		)
		(pad "1" smd rect
			(at -0.2667 0 90)
			(size 0.3048 0.381)
			(layers "F.Cu" "F.Mask" "F.Paste")
			(net "P5E_PEX1_STN5_TX_DN<95>")
		)
		(pad "2" smd rect
			(at 0.2667 0 90)
			(size 0.3048 0.381)
			(layers "F.Cu" "F.Mask" "F.Paste")
			(net "P5E_PEX1_STN5_TX_C_DN<95>")
		)
	)
)
